(kicad_pcb
	(version 20260206)
	(generator "pcbnew")
	(generator_version "10.0")
	(general
		(thickness 1.6)
		(legacy_teardrops no)
	)
	(paper "A4")
	(title_block
		(title "Bryce Canyon_F.DPB_16315-1-OCP.brd")
		(comment 1 "Bryce Canyon / footprints 1558-1563 of 2223")
	)
	(layers
		(0 "F.Cu" signal "TOP")
		(4 "In1.Cu" signal "L2GND")
		(6 "In2.Cu" signal "L3")
		(8 "In3.Cu" signal "L4GND")
		(10 "In4.Cu" signal "L5")
		(12 "In5.Cu" signal "L6VCC")
		(14 "In6.Cu" signal "L7VCC")
		(16 "In7.Cu" signal "L8")
		(18 "In8.Cu" signal "L9GND")
		(20 "In9.Cu" signal "L10")
		(22 "In10.Cu" signal "L11GND")
		(2 "B.Cu" signal "BOTTOM")
		(9 "F.Adhes" user "F.Adhesive")
		(11 "B.Adhes" user "B.Adhesive")
		(13 "F.Paste" user "Package Geometry/Pastemask Top")
		(15 "B.Paste" user "Package Geometry/Pastemask Bottom")
		(5 "F.SilkS" user "Ref Des/Silkscreen Top")
		(7 "B.SilkS" user "Ref Des/Silkscreen Bottom")
		(1 "F.Mask" user "Board Geometry/Soldermask Top")
		(3 "B.Mask" user "Board Geometry/Soldermask Bottom")
		(17 "Dwgs.User" user "User.Drawings")
		(19 "Cmts.User" user "User.Comments")
		(21 "Eco1.User" user "User.Eco1")
		(23 "Eco2.User" user "User.Eco2")
		(25 "Edge.Cuts" user "Board Geometry/Outline")
		(27 "Margin" user)
		(31 "F.CrtYd" user "Package Geometry/Place Bound Top")
		(29 "B.CrtYd" user "Package Geometry/Place Bound Bottom")
		(35 "F.Fab" user "Ref Des/Assembly Top")
		(33 "B.Fab" user "Ref Des/Assembly Bottom")
	)
	(footprint ""
		(layer "F.Cu")
		(at 322.549012 -127.360934)
		(property "Reference" "R316"
			(at 0 0 0)
			(layer "F.SilkS")
			(hide yes)
			(effects
				(font
					(size 1.27 1.27)
				)
			)
		)
		(property "Value" "91R3F-1-GP"
			(at -0.0254 -2.5146 0)
			(unlocked yes)
			(layer "F.Fab")
			(hide yes)
			(effects
				(font
					(size 1.016 1.016)
					(thickness 0.1524)
				)
			)
		)
		(property "Device Type" "R603H22"
			(at -0.0254 -4.0386 0)
			(unlocked yes)
			(layer "F.Fab")
			(hide yes)
			(effects
				(font
					(size 1.016 1.016)
					(thickness 0.1524)
				)
			)
		)
		(duplicate_pad_numbers_are_jumpers no)
		(fp_line
			(start -0.4826 0)
			(end -0.2032 0)
			(stroke
				(width 0.2032)
				(type default)
			)
			(layer "F.SilkS")
		)
		(fp_line
			(start 0.2032 0)
			(end 0.4826 0)
			(stroke
				(width 0.2032)
				(type default)
			)
			(layer "F.SilkS")
		)
		(fp_rect
			(start -0.5842 1.3335)
			(end 0.5842 -1.3335)
			(stroke
				(width 0)
				(type default)
			)
			(fill no)
			(layer "F.CrtYd")
		)
		(fp_rect
			(start -0.5842 1.3335)
			(end 0.5842 -1.3335)
			(stroke
				(width 0)
				(type default)
			)
			(fill no)
			(layer "F.Fab")
		)
		(pad "1" smd custom
			(at 0 -0.762)
			(size 0.2159 0.2159)
			(layers "F.Cu" "F.Mask" "F.Paste")
			(net "P5V_A_3")
			(options
				(clearance outline)
				(anchor circle)
			)
			(primitives
				(gr_poly
					(pts
						(arc
							(start -0.3302 -0.4318)
							(mid -0.402042 -0.402042)
							(end -0.4318 -0.3302)
						)
						(arc
							(start -0.4318 0.3302)
							(mid -0.402042 0.402042)
							(end -0.3302 0.4318)
						)
						(arc
							(start 0.3302 0.4318)
							(mid 0.402042 0.402042)
							(end 0.4318 0.3302)
						)
						(arc
							(start 0.4318 -0.3302)
							(mid 0.402042 -0.402042)
							(end 0.3302 -0.4318)
						)
					)
					(width 0)
					(fill yes)
				)
			)
		)
		(pad "2" smd custom
			(at 0 0.762)
			(size 0.2159 0.2159)
			(layers "F.Cu" "F.Mask" "F.Paste")
			(net "DRV_ACT_18")
			(options
				(clearance outline)
				(anchor circle)
			)
			(primitives
				(gr_poly
					(pts
						(arc
							(start -0.3302 -0.4318)
							(mid -0.402042 -0.402042)
							(end -0.4318 -0.3302)
						)
						(arc
							(start -0.4318 0.3302)
							(mid -0.402042 0.402042)
							(end -0.3302 0.4318)
						)
						(arc
							(start 0.3302 0.4318)
							(mid 0.402042 0.402042)
							(end 0.4318 0.3302)
						)
						(arc
							(start 0.4318 -0.3302)
							(mid 0.402042 -0.402042)
							(end 0.3302 -0.4318)
						)
					)
					(width 0)
					(fill yes)
				)
			)
		)
	)
	(footprint ""
		(layer "F.Cu")
		(at 114.724942 -280.498804 90)
		(property "Reference" "R215"
			(at 0 0 90)
			(layer "F.SilkS")
			(hide yes)
			(effects
				(font
					(size 1.27 1.27)
				)
			)
		)
		(property "Value" "200KR2F-L-GP"
			(at 0.064008 -3.993896 90)
			(unlocked yes)
			(layer "F.Fab")
			(hide yes)
			(effects
				(font
					(size 1.016 1.016)
					(thickness 0.1524)
				)
			)
		)
		(property "Device Type" "R402H16"
			(at 0.064008 -5.517896 90)
			(unlocked yes)
			(layer "F.Fab")
			(hide yes)
			(effects
				(font
					(size 1.016 1.016)
					(thickness 0.1524)
				)
			)
		)
		(duplicate_pad_numbers_are_jumpers no)
		(fp_line
			(start 0.508 -0.9398)
			(end -0.508 -0.9398)
			(stroke
				(width 0.1524)
				(type default)
			)
			(layer "F.SilkS")
		)
		(fp_line
			(start -0.508 -0.9398)
			(end -0.508 0.9398)
			(stroke
				(width 0.1524)
				(type default)
			)
			(layer "F.SilkS")
		)
		(fp_rect
			(start -0.508 0.9398)
			(end 0.508 -0.9398)
			(stroke
				(width 0)
				(type default)
			)
			(fill no)
			(layer "F.CrtYd")
		)
		(fp_rect
			(start -0.508 0.9398)
			(end 0.508 -0.9398)
			(stroke
				(width 0)
				(type default)
			)
			(fill no)
			(layer "F.Fab")
		)
		(pad "1" smd custom
			(at 0 -0.4445 90)
			(size 0.1397 0.1397)
			(layers "F.Cu" "F.Mask" "F.Paste")
			(net "SW_HDD_R3")
			(options
				(clearance outline)
				(anchor circle)
			)
			(primitives
				(gr_poly
					(pts
						(arc
							(start -0.1778 -0.2794)
							(mid -0.249642 -0.249642)
							(end -0.2794 -0.1778)
						)
						(arc
							(start -0.2794 0.1778)
							(mid -0.249642 0.249642)
							(end -0.1778 0.2794)
						)
						(arc
							(start 0.1778 0.2794)
							(mid 0.249642 0.249642)
							(end 0.2794 0.1778)
						)
						(arc
							(start 0.2794 -0.1778)
							(mid 0.249642 -0.249642)
							(end 0.1778 -0.2794)
						)
					)
					(width 0)
					(fill yes)
				)
			)
		)
		(pad "2" smd custom
			(at 0 0.4445 90)
			(size 0.1397 0.1397)
			(layers "F.Cu" "F.Mask" "F.Paste")
			(net "SW_HDD_N3")
			(options
				(clearance outline)
				(anchor circle)
			)
			(primitives
				(gr_poly
					(pts
						(arc
							(start -0.1778 -0.2794)
							(mid -0.249642 -0.249642)
							(end -0.2794 -0.1778)
						)
						(arc
							(start -0.2794 0.1778)
							(mid -0.249642 0.249642)
							(end -0.1778 0.2794)
						)
						(arc
							(start 0.1778 0.2794)
							(mid 0.249642 0.249642)
							(end 0.2794 0.1778)
						)
						(arc
							(start 0.2794 -0.1778)
							(mid 0.249642 -0.249642)
							(end 0.1778 -0.2794)
						)
					)
					(width 0)
					(fill yes)
				)
			)
		)
	)
	(footprint ""
		(layer "F.Cu")
		(at 241.68735 -349.162878 180)
		(property "Reference" "R25"
			(at 0 0 180)
			(layer "F.SilkS")
			(hide yes)
			(effects
				(font
					(size 1.27 1.27)
				)
			)
		)
		(property "Value" "16K2R2F-GP"
			(at 0.064008 -3.993896 180)
			(unlocked yes)
			(layer "F.Fab")
			(hide yes)
			(effects
				(font
					(size 1.016 1.016)
					(thickness 0.1524)
				)
			)
		)
		(property "Device Type" "R402H16"
			(at 0.064008 -5.517896 180)
			(unlocked yes)
			(layer "F.Fab")
			(hide yes)
			(effects
				(font
					(size 1.016 1.016)
					(thickness 0.1524)
				)
			)
		)
		(duplicate_pad_numbers_are_jumpers no)
		(fp_line
			(start 0.508 -0.9398)
			(end -0.508 -0.9398)
			(stroke
				(width 0.1524)
				(type default)
			)
			(layer "F.SilkS")
		)
		(fp_line
			(start -0.508 -0.9398)
			(end -0.508 0.9398)
			(stroke
				(width 0.1524)
				(type default)
			)
			(layer "F.SilkS")
		)
		(fp_rect
			(start -0.508 0.9398)
			(end 0.508 -0.9398)
			(stroke
				(width 0)
				(type default)
			)
			(fill no)
			(layer "F.CrtYd")
		)
		(fp_rect
			(start -0.508 0.9398)
			(end 0.508 -0.9398)
			(stroke
				(width 0)
				(type default)
			)
			(fill no)
			(layer "F.Fab")
		)
		(pad "1" smd custom
			(at 0 -0.4445 180)
			(size 0.1397 0.1397)
			(layers "F.Cu" "F.Mask" "F.Paste")
			(net "P5V_A_1")
			(options
				(clearance outline)
				(anchor circle)
			)
			(primitives
				(gr_poly
					(pts
						(arc
							(start -0.1778 -0.2794)
							(mid -0.249642 -0.249642)
							(end -0.2794 -0.1778)
						)
						(arc
							(start -0.2794 0.1778)
							(mid -0.249642 0.249642)
							(end -0.1778 0.2794)
						)
						(arc
							(start 0.1778 0.2794)
							(mid 0.249642 0.249642)
							(end 0.2794 0.1778)
						)
						(arc
							(start 0.2794 -0.1778)
							(mid 0.249642 -0.249642)
							(end 0.1778 -0.2794)
						)
					)
					(width 0)
					(fill yes)
				)
			)
		)
		(pad "2" smd custom
			(at 0 0.4445 180)
			(size 0.1397 0.1397)
			(layers "F.Cu" "F.Mask" "F.Paste")
			(net "P5V_A_1_SENSE")
			(options
				(clearance outline)
				(anchor circle)
			)
			(primitives
				(gr_poly
					(pts
						(arc
							(start -0.1778 -0.2794)
							(mid -0.249642 -0.249642)
							(end -0.2794 -0.1778)
						)
						(arc
							(start -0.2794 0.1778)
							(mid -0.249642 0.249642)
							(end -0.1778 0.2794)
						)
						(arc
							(start 0.1778 0.2794)
							(mid 0.249642 0.249642)
							(end 0.2794 0.1778)
						)
						(arc
							(start 0.2794 -0.1778)
							(mid 0.249642 -0.249642)
							(end 0.1778 -0.2794)
						)
					)
					(width 0)
					(fill yes)
				)
			)
		)
	)
	(footprint ""
		(layer "F.Cu")
		(at 231.267 -236.982 180)
		(property "Reference" "U7"
			(at 0 0 180)
			(layer "F.SilkS")
			(hide yes)
			(effects
				(font
					(size 1.27 1.27)
				)
			)
		)
		(property "Value" "TCA9555PWR-GP"
			(at 0 -6.9342 180)
			(unlocked yes)
			(layer "F.Fab")
			(hide yes)
			(effects
				(font
					(size 1.016 1.016)
					(thickness 0.1524)
				)
			)
		)
		(property "Device Type" "TSOIC24H48"
			(at 0 -8.5852 180)
			(unlocked yes)
			(layer "F.Fab")
			(hide yes)
			(effects
				(font
					(size 1.016 1.016)
					(thickness 0.1524)
				)
			)
		)
		(duplicate_pad_numbers_are_jumpers no)
		(fp_line
			(start 3.81 1.397)
			(end -4.2291 1.397)
			(stroke
				(width 0.1524)
				(type default)
			)
			(layer "F.SilkS")
		)
		(fp_line
			(start 3.81 -1.397)
			(end 3.81 1.397)
			(stroke
				(width 0.1524)
				(type default)
			)
			(layer "F.SilkS")
		)
		(fp_line
			(start -3.429 0)
			(end -4.2291 0.8001)
			(stroke
				(width 0.1524)
				(type default)
			)
			(layer "F.SilkS")
		)
		(fp_line
			(start -4.22656 3.81)
			(end -4.2291 1.397)
			(stroke
				(width 0.508)
				(type default)
			)
			(layer "F.SilkS")
		)
		(fp_line
			(start -4.2291 3.937)
			(end -4.2291 -1.397)
			(stroke
				(width 0.1524)
				(type default)
			)
			(layer "F.SilkS")
		)
		(fp_line
			(start -4.2291 -0.8001)
			(end -3.429 0)
			(stroke
				(width 0.1524)
				(type default)
			)
			(layer "F.SilkS")
		)
		(fp_line
			(start -4.2291 -1.397)
			(end 3.81 -1.397)
			(stroke
				(width 0.1524)
				(type default)
			)
			(layer "F.SilkS")
		)
		(fp_poly
			(pts
				(xy -3.90652 -1.8542) (xy 3.90652 -1.8542) (xy 3.90652 1.8542) (xy -3.90652 1.8542)
			)
			(stroke
				(width 0)
				(type default)
			)
			(fill yes)
			(layer "F.SilkS")
		)
		(fp_poly
			(pts
				(xy -4.2164 3.81) (xy 4.2164 3.81) (xy 4.22656 -3.81) (xy -4.2164 -3.81)
			)
			(stroke
				(width 0)
				(type default)
			)
			(fill no)
			(layer "F.CrtYd")
		)
		(fp_poly
			(pts
				(xy -4.22656 -3.81) (xy 4.22656 -3.81) (xy 4.22656 3.81) (xy -4.22656 3.81)
			)
			(stroke
				(width 0)
				(type default)
			)
			(fill no)
			(layer "F.Fab")
		)
		(pad "1" smd rect
			(at -3.57632 2.8194 180)
			(size 0.3556 1.524)
			(layers "F.Cu" "F.Mask" "F.Paste")
			(net "IO_EXP1_INT_N")
		)
		(pad "2" smd rect
			(at -2.92608 2.8194 180)
			(size 0.3556 1.524)
			(layers "F.Cu" "F.Mask" "F.Paste")
			(net "IO_EXP1_A1")
		)
		(pad "3" smd rect
			(at -2.27584 2.8194 180)
			(size 0.3556 1.524)
			(layers "F.Cu" "F.Mask" "F.Paste")
			(net "IO_EXP1_A2")
		)
		(pad "4" smd rect
			(at -1.6256 2.8194 180)
			(size 0.3556 1.524)
			(layers "F.Cu" "F.Mask" "F.Paste")
			(net "DRIVE_A_0_PWR")
		)
		(pad "5" smd rect
			(at -0.97536 2.8194 180)
			(size 0.3556 1.524)
			(layers "F.Cu" "F.Mask" "F.Paste")
			(net "DRIVE_A_1_PWR")
		)
		(pad "6" smd rect
			(at -0.32512 2.8194 180)
			(size 0.3556 1.524)
			(layers "F.Cu" "F.Mask" "F.Paste")
			(net "DRIVE_A_2_PWR")
		)
		(pad "7" smd rect
			(at 0.32512 2.8194 180)
			(size 0.3556 1.524)
			(layers "F.Cu" "F.Mask" "F.Paste")
			(net "DRIVE_A_3_PWR")
		)
		(pad "8" smd rect
			(at 0.97536 2.8194 180)
			(size 0.3556 1.524)
			(layers "F.Cu" "F.Mask" "F.Paste")
			(net "DRIVE_A_4_PWR")
		)
		(pad "9" smd rect
			(at 1.6256 2.8194 180)
			(size 0.3556 1.524)
			(layers "F.Cu" "F.Mask" "F.Paste")
			(net "DRIVE_A_5_PWR")
		)
		(pad "10" smd rect
			(at 2.27584 2.8194 180)
			(size 0.3556 1.524)
			(layers "F.Cu" "F.Mask" "F.Paste")
			(net "DRIVE_A_6_PWR")
		)
		(pad "11" smd rect
			(at 2.92608 2.8194 180)
			(size 0.3556 1.524)
			(layers "F.Cu" "F.Mask" "F.Paste")
			(net "DRIVE_A_7_PWR")
		)
		(pad "12" smd rect
			(at 3.57632 2.8194 180)
			(size 0.3556 1.524)
			(layers "F.Cu" "F.Mask" "F.Paste")
			(net "GND")
		)
		(pad "13" smd rect
			(at 3.57632 -2.8194 180)
			(size 0.3556 1.524)
			(layers "F.Cu" "F.Mask" "F.Paste")
			(net "DRIVE_A_8_PWR")
		)
		(pad "14" smd rect
			(at 2.92608 -2.8194 180)
			(size 0.3556 1.524)
			(layers "F.Cu" "F.Mask" "F.Paste")
			(net "DRIVE_A_9_PWR")
		)
		(pad "15" smd rect
			(at 2.27584 -2.8194 180)
			(size 0.3556 1.524)
			(layers "F.Cu" "F.Mask" "F.Paste")
			(net "DRIVE_A_10_PWR")
		)
		(pad "16" smd rect
			(at 1.6256 -2.8194 180)
			(size 0.3556 1.524)
			(layers "F.Cu" "F.Mask" "F.Paste")
			(net "DRIVE_A_11_PWR")
		)
		(pad "17" smd rect
			(at 0.97536 -2.8194 180)
			(size 0.3556 1.524)
			(layers "F.Cu" "F.Mask" "F.Paste")
			(net "DRIVE_A_12_PWR")
		)
		(pad "18" smd rect
			(at 0.32512 -2.8194 180)
			(size 0.3556 1.524)
			(layers "F.Cu" "F.Mask" "F.Paste")
			(net "DRIVE_A_13_PWR")
		)
		(pad "19" smd rect
			(at -0.32512 -2.8194 180)
			(size 0.3556 1.524)
			(layers "F.Cu" "F.Mask" "F.Paste")
			(net "DRIVE_A_14_PWR")
		)
		(pad "20" smd rect
			(at -0.97536 -2.8194 180)
			(size 0.3556 1.524)
			(layers "F.Cu" "F.Mask" "F.Paste")
			(net "DRIVE_A_15_PWR")
		)
		(pad "21" smd rect
			(at -1.6256 -2.8194 180)
			(size 0.3556 1.524)
			(layers "F.Cu" "F.Mask" "F.Paste")
			(net "IO_EXP1_A0")
		)
		(pad "22" smd rect
			(at -2.27584 -2.8194 180)
			(size 0.3556 1.524)
			(layers "F.Cu" "F.Mask" "F.Paste")
			(net "IO_EXP1_SCL")
		)
		(pad "23" smd rect
			(at -2.92608 -2.8194 180)
			(size 0.3556 1.524)
			(layers "F.Cu" "F.Mask" "F.Paste")
			(net "IO_EXP1_SDA")
		)
		(pad "24" smd rect
			(at -3.57632 -2.8194 180)
			(size 0.3556 1.524)
			(layers "F.Cu" "F.Mask" "F.Paste")
			(net "GPIO_VCC_U7")
		)
	)
	(footprint ""
		(layer "F.Cu")
		(at 134.460996 -291.077142 90)
		(property "Reference" "C80"
			(at 0 0 90)
			(layer "F.SilkS")
			(hide yes)
			(effects
				(font
					(size 1.27 1.27)
				)
			)
		)
		(property "Value" "SC10U16V6KX-2GP"
			(at -0.0762 -5.1308 90)
			(unlocked yes)
			(layer "F.Fab")
			(hide yes)
			(effects
				(font
					(size 1.016 1.016)
					(thickness 0.1524)
				)
			)
		)
		(property "Device Type" "C1206H71"
			(at -0.127 -6.6548 90)
			(unlocked yes)
			(layer "F.Fab")
			(hide yes)
			(effects
				(font
					(size 1.016 1.016)
					(thickness 0.1524)
				)
			)
		)
		(duplicate_pad_numbers_are_jumpers no)
		(fp_line
			(start 1.016 -2.2352)
			(end 1.016 -0.8382)
			(stroke
				(width 0.1524)
				(type default)
			)
			(layer "F.SilkS")
		)
		(fp_line
			(start -1.016 -2.2352)
			(end 1.016 -2.2352)
			(stroke
				(width 0.1524)
				(type default)
			)
			(layer "F.SilkS")
		)
		(fp_line
			(start -1.016 -0.8382)
			(end -1.016 -2.2352)
			(stroke
				(width 0.1524)
				(type default)
			)
			(layer "F.SilkS")
		)
		(fp_line
			(start 1.016 0.8382)
			(end 1.016 2.2352)
			(stroke
				(width 0.1524)
				(type default)
			)
			(layer "F.SilkS")
		)
		(fp_line
			(start 1.016 2.2352)
			(end -1.016 2.2352)
			(stroke
				(width 0.1524)
				(type default)
			)
			(layer "F.SilkS")
		)
		(fp_line
			(start -1.016 2.2352)
			(end -1.016 0.8382)
			(stroke
				(width 0.1524)
				(type default)
			)
			(layer "F.SilkS")
		)
		(fp_rect
			(start -1.0922 2.3114)
			(end 1.0922 -2.3114)
			(stroke
				(width 0)
				(type default)
			)
			(fill no)
			(layer "F.CrtYd")
		)
		(fp_poly
			(pts
				(xy 1.0922 -2.3114) (xy 1.0922 2.3114) (xy -1.0922 2.3114) (xy -1.0922 -2.3114)
			)
			(stroke
				(width 0)
				(type default)
			)
			(fill no)
			(layer "F.Fab")
		)
		(pad "1" smd rect
			(at 0 -1.397 90)
			(size 1.651 1.27)
			(layers "F.Cu" "F.Mask" "F.Paste")
			(net "P5V_HDD3")
		)
		(pad "2" smd rect
			(at 0 1.397 90)
			(size 1.651 1.27)
			(layers "F.Cu" "F.Mask" "F.Paste")
			(net "GND")
		)
	)
	(footprint ""
		(layer "F.Cu")
		(at 458.299058 -245.269004 -90)
		(property "Reference" "R500"
			(at 0 0 270)
			(layer "F.SilkS")
			(hide yes)
			(effects
				(font
					(size 1.27 1.27)
				)
			)
		)
		(property "Value" "4K7R2J-2-GP"
			(at 0.064008 -3.993896 270)
			(unlocked yes)
			(layer "F.Fab")
			(hide yes)
			(effects
				(font
					(size 1.016 1.016)
					(thickness 0.1524)
				)
			)
		)
		(property "Device Type" "R402H16"
			(at 0.064008 -5.517896 270)
			(unlocked yes)
			(layer "F.Fab")
			(hide yes)
			(effects
				(font
					(size 1.016 1.016)
					(thickness 0.1524)
				)
			)
		)
		(duplicate_pad_numbers_are_jumpers no)
		(fp_line
			(start -0.508 -0.9398)
			(end -0.508 0.9398)
			(stroke
				(width 0.1524)
				(type default)
			)
			(layer "F.SilkS")
		)
		(fp_line
			(start 0.508 -0.9398)
			(end -0.508 -0.9398)
			(stroke
				(width 0.1524)
				(type default)
			)
			(layer "F.SilkS")
		)
		(fp_rect
			(start -0.508 0.9398)
			(end 0.508 -0.9398)
			(stroke
				(width 0)
				(type default)
			)
			(fill no)
			(layer "F.CrtYd")
		)
		(fp_rect
			(start -0.508 0.9398)
			(end 0.508 -0.9398)
			(stroke
				(width 0)
				(type default)
			)
			(fill no)
			(layer "F.Fab")
		)
		(pad "1" smd custom
			(at 0 -0.4445 270)
			(size 0.1397 0.1397)
			(layers "F.Cu" "F.Mask" "F.Paste")
			(net "DRIVE_A_11_FLT_LED")
			(options
				(clearance outline)
				(anchor circle)
			)
			(primitives
				(gr_poly
					(pts
						(arc
							(start -0.1778 -0.2794)
							(mid -0.249642 -0.249642)
							(end -0.2794 -0.1778)
						)
						(arc
							(start -0.2794 0.1778)
							(mid -0.249642 0.249642)
							(end -0.1778 0.2794)
						)
						(arc
							(start 0.1778 0.2794)
							(mid 0.249642 0.249642)
							(end 0.2794 0.1778)
						)
						(arc
							(start 0.2794 -0.1778)
							(mid 0.249642 -0.249642)
							(end 0.1778 -0.2794)
						)
					)
					(width 0)
					(fill yes)
				)
			)
		)
		(pad "2" smd custom
			(at 0 0.4445 270)
			(size 0.1397 0.1397)
			(layers "F.Cu" "F.Mask" "F.Paste")
			(net "GND")
			(options
				(clearance outline)
				(anchor circle)
			)
			(primitives
				(gr_poly
					(pts
						(arc
							(start -0.1778 -0.2794)
							(mid -0.249642 -0.249642)
							(end -0.2794 -0.1778)
						)
						(arc
							(start -0.2794 0.1778)
							(mid -0.249642 0.249642)
							(end -0.1778 0.2794)
						)
						(arc
							(start 0.1778 0.2794)
							(mid 0.249642 0.249642)
							(end 0.2794 0.1778)
						)
						(arc
							(start 0.2794 -0.1778)
							(mid 0.249642 -0.249642)
							(end 0.1778 -0.2794)
						)
					)
					(width 0)
					(fill yes)
				)
			)
		)
	)
)
